(kicad_pcb
	(version 20241229)
	(generator "pcbnew")
	(generator_version "9.0")
	(general
		(thickness 1.711)
		(legacy_teardrops no)
	)
	(paper "A4")
	(title_block
		(title "Antmicro Baseboard for Jetson AGX Thor")
		(date "2026-02-18")
		(rev "1.1.0")
		(company "Antmicro Ltd")
		(comment 1 "www.antmicro.com")
		(comment 9 "footprints 381-385 of 1170")
	)
	(layers
		(0 "F.Cu" signal)
		(4 "In1.Cu" signal)
		(6 "In2.Cu" signal)
		(8 "In3.Cu" signal)
		(10 "In4.Cu" jumper)
		(12 "In5.Cu" signal)
		(14 "In6.Cu" signal)
		(16 "In7.Cu" signal)
		(18 "In8.Cu" signal)
		(2 "B.Cu" signal)
		(9 "F.Adhes" user "F.Adhesive")
		(11 "B.Adhes" user "B.Adhesive")
		(13 "F.Paste" user)
		(15 "B.Paste" user)
		(5 "F.SilkS" user "F.Silkscreen")
		(7 "B.SilkS" user "B.Silkscreen")
		(1 "F.Mask" user)
		(3 "B.Mask" user)
		(17 "Dwgs.User" user "User.Drawings")
		(19 "Cmts.User" user "User.Comments")
		(21 "Eco1.User" user "User.Eco1")
		(23 "Eco2.User" user "User.Eco2")
		(25 "Edge.Cuts" user)
		(27 "Margin" user)
		(31 "F.CrtYd" user "F.Courtyard")
		(29 "B.CrtYd" user "B.Courtyard")
		(35 "F.Fab" user)
		(33 "B.Fab" user)
	)
	(footprint "antmicro-footprints:TP_SMD_0.75mm"
		(layer "F.Cu")
		(at 68.85 58.25 90)
		(property "Reference" "TP25"
			(at -0.15 0.9 180)
			(layer "F.SilkS")
			(effects
				(font
					(size 0.7 0.7)
					(thickness 0.15)
				)
				(justify left bottom)
			)
		)
		(property "Value" "TP_0.75mm_SMD"
			(at 0 1.2 90)
			(layer "F.Fab")
			(effects
				(font
					(size 0.7 0.7)
					(thickness 0.15)
				)
				(justify left bottom)
			)
		)
		(property "Description" "SMT test point"
			(at 0 0 90)
			(layer "F.Fab")
			(hide yes)
			(effects
				(font
					(size 1.27 1.27)
					(thickness 0.15)
				)
			)
		)
		(property "MPN" ""
			(at 0 0 90)
			(unlocked yes)
			(layer "F.Fab")
			(hide yes)
			(effects
				(font
					(size 1 1)
					(thickness 0.15)
				)
			)
		)
		(property "Manufacturer" ""
			(at 0 0 90)
			(unlocked yes)
			(layer "F.Fab")
			(hide yes)
			(effects
				(font
					(size 1 1)
					(thickness 0.15)
				)
			)
		)
		(property "Author" "Antmicro"
			(at 0 0 90)
			(unlocked yes)
			(layer "F.Fab")
			(hide yes)
			(effects
				(font
					(size 1 1)
					(thickness 0.15)
				)
			)
		)
		(property "License" "Apache-2.0"
			(at 0 0 90)
			(unlocked yes)
			(layer "F.Fab")
			(hide yes)
			(effects
				(font
					(size 1 1)
					(thickness 0.15)
				)
			)
		)
		(sheetname "/CSI/")
		(sheetfile "csi.kicad_sch")
		(attr exclude_from_pos_files exclude_from_bom)
		(fp_circle
			(center 0 0)
			(end 0.475 0)
			(stroke
				(width 0.05)
				(type default)
			)
			(fill no)
			(layer "F.CrtYd")
		)
		(fp_text user "${REFERENCE}"
			(at -0.4 2.7 90)
			(layer "F.Fab")
			(effects
				(font
					(size 0.7 0.7)
					(thickness 0.15)
				)
				(justify left bottom)
			)
		)
		(fp_text user "Author: Antmicro"
			(at -0.4 3.901 90)
			(layer "F.Fab")
			(effects
				(font
					(size 0.7 0.7)
					(thickness 0.15)
				)
				(justify left bottom)
			)
		)
		(fp_text user "License: Apache-2.0"
			(at -0.4 5.101 90)
			(layer "F.Fab")
			(effects
				(font
					(size 0.7 0.7)
					(thickness 0.15)
				)
				(justify left bottom)
			)
		)
		(pad "1" smd circle
			(at 0 0 90)
			(size 0.75 0.75)
			(layers "F.Cu" "F.Mask")
			(net 1049 "/CSI/MUX_I2C_6_SDA")
			(pinfunction "1")
			(pintype "passive")
		)
	)
	(footprint "antmicro-footprints:LED_0603_1608Metric_G"
		(layer "F.Cu")
		(at 235.540532 134.323 180)
		(descr "LED SMD 0603 Green")
		(tags "LED SMD 0603 Green")
		(property "Reference" "D49"
			(at -0.459468 -0.799999 0)
			(layer "F.SilkS")
			(effects
				(font
					(size 0.7 0.7)
					(thickness 0.15)
				)
				(justify right top)
			)
		)
		(property "Value" "LED_G_0603_LTST-C190GKT"
			(at -0.001 1.599 0)
			(layer "F.Fab")
			(effects
				(font
					(size 0.7 0.7)
					(thickness 0.15)
				)
				(justify right top)
			)
		)
		(property "Datasheet" "https://media.digikey.com/pdf/Data%20Sheets/Lite-On%20PDFs/LTST-C190GKT.pdf"
			(at 0 0 0)
			(layer "F.Fab")
			(hide yes)
			(effects
				(font
					(size 1.27 1.27)
					(thickness 0.15)
				)
			)
		)
		(property "Description" "LED, Green, SMD, 0603, 20 mA, 2.1 V, 569 nm"
			(at 0 0 0)
			(layer "F.Fab")
			(hide yes)
			(effects
				(font
					(size 1.27 1.27)
					(thickness 0.15)
				)
			)
		)
		(property "MPN" "LTST-C190GKT"
			(at 0 0 180)
			(unlocked yes)
			(layer "F.Fab")
			(hide yes)
			(effects
				(font
					(size 1 1)
					(thickness 0.15)
				)
			)
		)
		(property "Manufacturer" "Lite-On"
			(at 0 0 180)
			(unlocked yes)
			(layer "F.Fab")
			(hide yes)
			(effects
				(font
					(size 1 1)
					(thickness 0.15)
				)
			)
		)
		(property "Author" "Antmicro"
			(at 0 0 180)
			(unlocked yes)
			(layer "F.Fab")
			(hide yes)
			(effects
				(font
					(size 1 1)
					(thickness 0.15)
				)
			)
		)
		(property "License" "Apache-2.0"
			(at 0 0 180)
			(unlocked yes)
			(layer "F.Fab")
			(hide yes)
			(effects
				(font
					(size 1 1)
					(thickness 0.15)
				)
			)
		)
		(property "Color" "Green"
			(at 0 0 180)
			(unlocked yes)
			(layer "F.Fab")
			(hide yes)
			(effects
				(font
					(size 1 1)
					(thickness 0.15)
				)
			)
		)
		(sheetname "/USB Hub/")
		(sheetfile "usb_hub.kicad_sch")
		(attr smd)
		(fp_line
			(start 0.22 0.35)
			(end -0.22 0.35)
			(stroke
				(width 0.15)
				(type solid)
			)
			(layer "F.SilkS")
		)
		(fp_line
			(start 0.22 -0.35)
			(end -0.22 -0.35)
			(stroke
				(width 0.15)
				(type solid)
			)
			(layer "F.SilkS")
		)
		(fp_line
			(start 0.105328 0.201008)
			(end 0.105329 -0.198992)
			(stroke
				(width 0.1)
				(type solid)
			)
			(layer "F.SilkS")
		)
		(fp_line
			(start 0.105328 0.201008)
			(end -0.094672 0.001008)
			(stroke
				(width 0.1)
				(type solid)
			)
			(layer "F.SilkS")
		)
		(fp_line
			(start 0.105328 0.001008)
			(end 0.240001 0.001)
			(stroke
				(width 0.1)
				(type solid)
			)
			(layer "F.SilkS")
		)
		(fp_line
			(start -0.094672 0.201008)
			(end -0.094672 -0.198992)
			(stroke
				(width 0.1)
				(type solid)
			)
			(layer "F.SilkS")
		)
		(fp_line
			(start -0.094672 0.001008)
			(end 0.105329 -0.198992)
			(stroke
				(width 0.1)
				(type solid)
			)
			(layer "F.SilkS")
		)
		(fp_line
			(start -0.094672 0.001008)
			(end -0.24 0.001008)
			(stroke
				(width 0.1)
				(type solid)
			)
			(layer "F.SilkS")
		)
		(fp_line
			(start -1.18 -0.319)
			(end -1.18 0.321)
			(stroke
				(width 0.15)
				(type solid)
			)
			(layer "F.SilkS")
		)
		(fp_poly
			(pts
				(xy 1.25 0.65) (xy -1.25 0.65) (xy -1.25 -0.65) (xy 1.25 -0.65)
			)
			(stroke
				(width 0.05)
				(type solid)
			)
			(fill no)
			(layer "F.CrtYd")
		)
		(fp_line
			(start 0.599 0)
			(end 0.200999 0)
			(stroke
				(width 0.15)
				(type solid)
			)
			(layer "F.Fab")
		)
		(fp_line
			(start 0.201 0.2)
			(end 0.200999 0)
			(stroke
				(width 0.15)
				(type solid)
			)
			(layer "F.Fab")
		)
		(fp_line
			(start 0.201 -0.202)
			(end -0.101 0)
			(stroke
				(width 0.15)
				(type solid)
			)
			(layer "F.Fab")
		)
		(fp_line
			(start 0.200999 0)
			(end 0.201 -0.202)
			(stroke
				(width 0.15)
				(type solid)
			)
			(layer "F.Fab")
		)
		(fp_line
			(start -0.101 0)
			(end 0.201 0.2)
			(stroke
				(width 0.15)
				(type solid)
			)
			(layer "F.Fab")
		)
		(fp_line
			(start -0.199 0.2)
			(end -0.199 0.1)
			(stroke
				(width 0.15)
				(type solid)
			)
			(layer "F.Fab")
		)
		(fp_line
			(start -0.199 0)
			(end -0.597 0)
			(stroke
				(width 0.15)
				(type solid)
			)
			(layer "F.Fab")
		)
		(fp_line
			(start -0.199 -0.202)
			(end -0.199 0.1)
			(stroke
				(width 0.15)
				(type solid)
			)
			(layer "F.Fab")
		)
		(fp_poly
			(pts
				(xy 0.848 0.4) (xy -0.85 0.4) (xy -0.85 -0.402) (xy 0.848 -0.401999)
			)
			(stroke
				(width 0.15)
				(type solid)
			)
			(fill no)
			(layer "F.Fab")
		)
		(fp_text user "${REFERENCE}"
			(at -1.4224 5.999 0)
			(layer "F.Fab")
			(effects
				(font
					(size 0.7 0.7)
					(thickness 0.15)
				)
				(justify right top)
			)
		)
		(fp_text user "License: Apache-2.0"
			(at -1.4224 3.599 0)
			(layer "F.Fab")
			(effects
				(font
					(size 0.7 0.7)
					(thickness 0.15)
				)
				(justify right top)
			)
		)
		(fp_text user "Author: Antmicro"
			(at -1.4224 4.799 0)
			(layer "F.Fab")
			(effects
				(font
					(size 0.7 0.7)
					(thickness 0.15)
				)
				(justify right top)
			)
		)
		(pad "1" smd roundrect
			(at -0.7 0)
			(size 0.8 1)
			(layers "F.Cu" "F.Mask" "F.Paste")
			(roundrect_rratio 0.2)
			(net 1 "GND")
			(pinfunction "C")
			(pintype "passive")
		)
		(pad "2" smd roundrect
			(at 0.7 0)
			(size 0.8 1)
			(layers "F.Cu" "F.Mask" "F.Paste")
			(roundrect_rratio 0.2)
			(net 1390 "Net-(D49-A)")
			(pinfunction "A")
			(pintype "passive")
		)
	)
	(footprint "antmicro-footprints:R_0402_1005Metric"
		(layer "F.Cu")
		(at 232.540532 134.323 180)
		(descr "Resistor SMD 0402")
		(tags "resistor SMD 0402")
		(property "Reference" "R260"
			(at -1.122484 -0.772697 0)
			(layer "F.SilkS")
			(effects
				(font
					(size 0.7 0.7)
					(thickness 0.15)
				)
				(justify right top)
			)
		)
		(property "Value" "R_470R_0402"
			(at -1.011843 1.772046 0)
			(layer "F.Fab")
			(effects
				(font
					(size 0.7 0.7)
					(thickness 0.15)
				)
				(justify right top)
			)
		)
		(property "Datasheet" "https://www.bourns.com/docs/product-datasheets/cr.pdf"
			(at 0 0 0)
			(layer "F.Fab")
			(hide yes)
			(effects
				(font
					(size 1.27 1.27)
					(thickness 0.15)
				)
			)
		)
		(property "Description" "SMD Chip Resistor, 470 ohm, ± 1%, 62.5 mW, 0402 [1005 Metric], Thick Film, General Purpose"
			(at 0 0 0)
			(layer "F.Fab")
			(hide yes)
			(effects
				(font
					(size 1.27 1.27)
					(thickness 0.15)
				)
			)
		)
		(property "Manufacturer" "Bourns"
			(at 0 0 180)
			(unlocked yes)
			(layer "F.Fab")
			(hide yes)
			(effects
				(font
					(size 1 1)
					(thickness 0.15)
				)
			)
		)
		(property "MPN" "CR0402-FX-4700GLF"
			(at 0 0 180)
			(unlocked yes)
			(layer "F.Fab")
			(hide yes)
			(effects
				(font
					(size 1 1)
					(thickness 0.15)
				)
			)
		)
		(property "Val" "470R"
			(at 0 0 180)
			(unlocked yes)
			(layer "F.Fab")
			(hide yes)
			(effects
				(font
					(size 1 1)
					(thickness 0.15)
				)
			)
		)
		(property "License" "Apache-2.0"
			(at 0 0 180)
			(unlocked yes)
			(layer "F.Fab")
			(hide yes)
			(effects
				(font
					(size 1 1)
					(thickness 0.15)
				)
			)
		)
		(property "Author" "Antmicro"
			(at 0 0 180)
			(unlocked yes)
			(layer "F.Fab")
			(hide yes)
			(effects
				(font
					(size 1 1)
					(thickness 0.15)
				)
			)
		)
		(property "Tolerance" "1%"
			(at 0 0 180)
			(unlocked yes)
			(layer "F.Fab")
			(hide yes)
			(effects
				(font
					(size 1 1)
					(thickness 0.15)
				)
			)
		)
		(sheetname "/USB Hub/")
		(sheetfile "usb_hub.kicad_sch")
		(attr smd)
		(fp_poly
			(pts
				(xy -0.925 -0.47) (xy 0.925 -0.47) (xy 0.925 0.47) (xy -0.925 0.47)
			)
			(stroke
				(width 0.05)
				(type default)
			)
			(fill no)
			(layer "F.CrtYd")
		)
		(fp_poly
			(pts
				(xy -0.5 -0.25) (xy 0.5 -0.25) (xy 0.5 0.25) (xy -0.5 0.25)
			)
			(stroke
				(width 0.15)
				(type solid)
			)
			(fill no)
			(layer "F.Fab")
		)
		(fp_text user "License: Apache-2.0"
			(at -0.949999 5.169 0)
			(layer "F.Fab")
			(effects
				(font
					(size 0.7 0.7)
					(thickness 0.15)
				)
				(justify right top)
			)
		)
		(fp_text user "${REFERENCE}"
			(at -0.95 3.168 0)
			(layer "F.Fab")
			(effects
				(font
					(size 0.7 0.7)
					(thickness 0.15)
				)
				(justify right top)
			)
		)
		(fp_text user "Author: Antmicro"
			(at -0.95 4.169 0)
			(layer "F.Fab")
			(effects
				(font
					(size 0.7 0.7)
					(thickness 0.15)
				)
				(justify right top)
			)
		)
		(pad "1" smd roundrect
			(at -0.48 0 180)
			(size 0.59 0.64)
			(layers "F.Cu" "F.Mask" "F.Paste")
			(roundrect_rratio 0.25)
			(net 1390 "Net-(D49-A)")
			(pintype "passive")
		)
		(pad "2" smd roundrect
			(at 0.48 0 180)
			(size 0.59 0.64)
			(layers "F.Cu" "F.Mask" "F.Paste")
			(roundrect_rratio 0.25)
			(net 115 "/USB Hub/USBC4_VBUS")
			(pintype "passive")
		)
	)
	(footprint "antmicro-footprints:C_0402_1005Metric"
		(layer "F.Cu")
		(at 206 79.205)
		(descr "Capacitor SMD 0402")
		(tags "capacitor SMD 0402")
		(property "Reference" "C119"
			(at 0.921064 0.365 0)
			(layer "F.SilkS")
			(effects
				(font
					(size 0.7 0.7)
					(thickness 0.15)
				)
				(justify left bottom)
			)
		)
		(property "Value" "C_100n_0402"
			(at -1.022927 2.155213 0)
			(layer "F.Fab")
			(effects
				(font
					(size 0.7 0.7)
					(thickness 0.15)
				)
				(justify left bottom)
			)
		)
		(property "Datasheet" "https://www.murata.com/products/productdetail?partno=GRM155R61H104KE14%23"
			(at 0 0 0)
			(layer "F.Fab")
			(hide yes)
			(effects
				(font
					(size 1.27 1.27)
					(thickness 0.15)
				)
			)
		)
		(property "Description" "SMD Multilayer Ceramic Capacitor, 0.1 µF, 50 V, 0402 [1005 Metric], ± 10%, X5R, GRM Series"
			(at 0 0 0)
			(layer "F.Fab")
			(hide yes)
			(effects
				(font
					(size 1.27 1.27)
					(thickness 0.15)
				)
			)
		)
		(property "Manufacturer" "Murata"
			(at 0 0 0)
			(unlocked yes)
			(layer "F.Fab")
			(hide yes)
			(effects
				(font
					(size 1 1)
					(thickness 0.15)
				)
			)
		)
		(property "MPN" "GRM155R61H104KE14D"
			(at 0 0 0)
			(unlocked yes)
			(layer "F.Fab")
			(hide yes)
			(effects
				(font
					(size 1 1)
					(thickness 0.15)
				)
			)
		)
		(property "Val" "100n"
			(at 0 0 0)
			(unlocked yes)
			(layer "F.Fab")
			(hide yes)
			(effects
				(font
					(size 1 1)
					(thickness 0.15)
				)
			)
		)
		(property "License" "Apache-2.0"
			(at 0 0 0)
			(unlocked yes)
			(layer "F.Fab")
			(hide yes)
			(effects
				(font
					(size 1 1)
					(thickness 0.15)
				)
			)
		)
		(property "Author" "Antmicro"
			(at 0 0 0)
			(unlocked yes)
			(layer "F.Fab")
			(hide yes)
			(effects
				(font
					(size 1 1)
					(thickness 0.15)
				)
			)
		)
		(property "Voltage" "50V"
			(at 0 0 0)
			(unlocked yes)
			(layer "F.Fab")
			(hide yes)
			(effects
				(font
					(size 1 1)
					(thickness 0.15)
				)
			)
		)
		(property "Dielectric" "X5R"
			(at 0 0 0)
			(unlocked yes)
			(layer "F.Fab")
			(hide yes)
			(effects
				(font
					(size 1 1)
					(thickness 0.15)
				)
			)
		)
		(sheetname "/USB Debug, PD/")
		(sheetfile "usb_debug_pd.kicad_sch")
		(attr smd)
		(fp_rect
			(start -0.925 -0.47)
			(end 0.925 0.47)
			(stroke
				(width 0.05)
				(type default)
			)
			(fill no)
			(layer "F.CrtYd")
		)
		(fp_line
			(start -0.494 -0.25)
			(end 0.504 -0.25)
			(stroke
				(width 0.15)
				(type solid)
			)
			(layer "F.Fab")
		)
		(fp_line
			(start -0.494 0.248)
			(end -0.494 -0.25)
			(stroke
				(width 0.15)
				(type solid)
			)
			(layer "F.Fab")
		)
		(fp_line
			(start 0.504 -0.25)
			(end 0.504 0.248)
			(stroke
				(width 0.15)
				(type solid)
			)
			(layer "F.Fab")
		)
		(fp_line
			(start 0.504 0.248)
			(end -0.494 0.248)
			(stroke
				(width 0.15)
				(type solid)
			)
			(layer "F.Fab")
		)
		(fp_text user "Author: Antmicro"
			(at -0.939 3.399 0)
			(layer "F.Fab")
			(effects
				(font
					(size 0.7 0.7)
					(thickness 0.15)
				)
				(justify left bottom)
			)
		)
		(fp_text user "${REFERENCE}"
			(at -0.939 4.599 0)
			(layer "F.Fab")
			(effects
				(font
					(size 0.7 0.7)
					(thickness 0.15)
				)
				(justify left bottom)
			)
		)
		(fp_text user "License: Apache-2.0"
			(at -0.939 5.799 0)
			(layer "F.Fab")
			(effects
				(font
					(size 0.7 0.7)
					(thickness 0.15)
				)
				(justify left bottom)
			)
		)
		(pad "1" smd roundrect
			(at -0.48 0)
			(size 0.59 0.64)
			(layers "F.Cu" "F.Mask" "F.Paste")
			(roundrect_rratio 0.25)
			(net 2 "+3V3")
			(pintype "passive")
		)
		(pad "2" smd roundrect
			(at 0.48 0)
			(size 0.59 0.64)
			(layers "F.Cu" "F.Mask" "F.Paste")
			(roundrect_rratio 0.25)
			(net 1 "GND")
			(pintype "passive")
		)
	)
	(footprint "antmicro-footprints:R_0402_1005Metric"
		(layer "F.Cu")
		(at 142.59 131.32 90)
		(descr "Resistor SMD 0402")
		(tags "resistor SMD 0402")
		(property "Reference" "R363"
			(at -0.98 1.51 90)
			(layer "F.SilkS")
			(effects
				(font
					(size 0.7 0.7)
					(thickness 0.15)
				)
				(justify left bottom)
			)
		)
		(property "Value" "R_100k_0402"
			(at -1.011843 1.772047 90)
			(layer "F.Fab")
			(effects
				(font
					(size 0.7 0.7)
					(thickness 0.15)
				)
				(justify left bottom)
			)
		)
		(property "Datasheet" "https://www.bourns.com/docs/product-datasheets/cr.pdf"
			(at 0 0 90)
			(layer "F.Fab")
			(hide yes)
			(effects
				(font
					(size 1.27 1.27)
					(thickness 0.15)
				)
			)
		)
		(property "Description" "SMD Chip Resistor, 100 kohm, ± 1%, 62.5 mW, 0402 [1005 Metric], Thick Film, General Purpose"
			(at 0 0 90)
			(layer "F.Fab")
			(hide yes)
			(effects
				(font
					(size 1.27 1.27)
					(thickness 0.15)
				)
			)
		)
		(property "MPN" "CR0402-FX-1003GLF"
			(at 0 0 90)
			(unlocked yes)
			(layer "F.Fab")
			(hide yes)
			(effects
				(font
					(size 1 1)
					(thickness 0.15)
				)
			)
		)
		(property "Manufacturer" "Bourns"
			(at 0 0 90)
			(unlocked yes)
			(layer "F.Fab")
			(hide yes)
			(effects
				(font
					(size 1 1)
					(thickness 0.15)
				)
			)
		)
		(property "License" "Apache-2.0"
			(at 0 0 90)
			(unlocked yes)
			(layer "F.Fab")
			(hide yes)
			(effects
				(font
					(size 1 1)
					(thickness 0.15)
				)
			)
		)
		(property "Author" "Antmicro"
			(at 0 0 90)
			(unlocked yes)
			(layer "F.Fab")
			(hide yes)
			(effects
				(font
					(size 1 1)
					(thickness 0.15)
				)
			)
		)
		(property "Val" "100k"
			(at 0 0 90)
			(unlocked yes)
			(layer "F.Fab")
			(hide yes)
			(effects
				(font
					(size 1 1)
					(thickness 0.15)
				)
			)
		)
		(property "Tolerance" "1%"
			(at 0 0 90)
			(unlocked yes)
			(layer "F.Fab")
			(hide yes)
			(effects
				(font
					(size 1 1)
					(thickness 0.15)
				)
			)
		)
		(sheetname "/SoM_Power/")
		(sheetfile "som_power.kicad_sch")
		(attr smd)
		(fp_rect
			(start -0.925 -0.47)
			(end 0.925 0.47)
			(stroke
				(width 0.05)
				(type default)
			)
			(fill no)
			(layer "F.CrtYd")
		)
		(fp_rect
			(start -0.5 -0.25)
			(end 0.5 0.25)
			(stroke
				(width 0.15)
				(type solid)
			)
			(fill no)
			(layer "F.Fab")
		)
		(fp_text user "License: Apache-2.0"
			(at -0.95 5.169 90)
			(layer "F.Fab")
			(effects
				(font
					(size 0.7 0.7)
					(thickness 0.15)
				)
				(justify left bottom)
			)
		)
		(fp_text user "${REFERENCE}"
			(at -0.95 3.168 90)
			(layer "F.Fab")
			(effects
				(font
					(size 0.7 0.7)
					(thickness 0.15)
				)
				(justify left bottom)
			)
		)
		(fp_text user "Author: Antmicro"
			(at -0.95 4.169 90)
			(layer "F.Fab")
			(effects
				(font
					(size 0.7 0.7)
					(thickness 0.15)
				)
				(justify left bottom)
			)
		)
		(pad "1" smd roundrect
			(at -0.48 0 90)
			(size 0.59 0.64)
			(layers "F.Cu" "F.Mask" "F.Paste")
			(roundrect_rratio 0.25)
			(net 883 "Net-(Q10-G)")
			(pintype "passive")
		)
		(pad "2" smd roundrect
			(at 0.48 0 90)
			(size 0.59 0.64)
			(layers "F.Cu" "F.Mask" "F.Paste")
			(roundrect_rratio 0.25)
			(net 4 "+3V3_AON")
			(pintype "passive")
		)
	)
)
